(kicad_pcb
	(version 20241229)
	(generator "pcbnew")
	(generator_version "9.0")
	(general
		(thickness 1.294)
		(legacy_teardrops no)
	)
	(paper "A3")
	(title_block
		(title "Kintex 410T devboard")
		(date "2024-04-03")
		(rev "1.1.2")
		(comment 9 "footprints 517-520 of 975")
	)
	(layers
		(0 "F.Cu" mixed)
		(4 "In1.Cu" power)
		(6 "In2.Cu" power)
		(8 "In3.Cu" mixed)
		(10 "In4.Cu" power)
		(12 "In5.Cu" mixed)
		(14 "In6.Cu" power)
		(16 "In7.Cu" mixed)
		(18 "In8.Cu" power)
		(2 "B.Cu" mixed)
		(9 "F.Adhes" user "F.Adhesive")
		(11 "B.Adhes" user "B.Adhesive")
		(13 "F.Paste" user)
		(15 "B.Paste" user)
		(5 "F.SilkS" user "F.Silkscreen")
		(7 "B.SilkS" user "B.Silkscreen")
		(1 "F.Mask" user)
		(3 "B.Mask" user)
		(17 "Dwgs.User" user "User.Drawings")
		(19 "Cmts.User" user "User.Comments")
		(21 "Eco1.User" user "User.Eco1")
		(23 "Eco2.User" user "User.Eco2")
		(25 "Edge.Cuts" user)
		(27 "Margin" user)
		(31 "F.CrtYd" user "F.Courtyard")
		(29 "B.CrtYd" user "B.Courtyard")
		(35 "F.Fab" user)
		(33 "B.Fab" user)
	)
	(footprint "antmicro-footprints:MicroSD_DM3AT-SF-PEJM5"
		(layer "B.Cu")
		(at 261.027 136.677 -90)
		(descr "Micro SD, SMD, right-angle, push-pull")
		(tags "Micro SD")
		(property "Reference" "J23"
			(at 1.753 8.907 90)
			(layer "B.SilkS")
			(effects
				(font
					(size 0.7 0.7)
					(thickness 0.15)
				)
				(justify left bottom mirror)
			)
		)
		(property "Value" "DM3AT-SF-PEJM5"
			(at 0 -9.6 90)
			(layer "B.Fab")
			(effects
				(font
					(size 0.7 0.7)
					(thickness 0.15)
				)
				(justify left bottom mirror)
			)
		)
		(property "Description" "Memory Card Connector, MicroSD, Push-Push, 8 Contacts, Copper Alloy, Gold Plated Contacts, DM3"
			(at 0 0 270)
			(layer "F.Fab")
			(hide yes)
			(effects
				(font
					(size 1.27 1.27)
					(thickness 0.15)
				)
			)
		)
		(property "Author" "Antmicro"
			(at 124.35 397.704 0)
			(layer "B.Fab")
			(hide yes)
			(effects
				(font
					(size 1 1)
					(thickness 0.15)
				)
				(justify mirror)
			)
		)
		(property "License" "Apache-2.0"
			(at 124.35 397.704 0)
			(layer "B.Fab")
			(hide yes)
			(effects
				(font
					(size 1 1)
					(thickness 0.15)
				)
				(justify mirror)
			)
		)
		(property "MPN" "DM3AT-SF-PEJM5"
			(at 124.35 397.704 0)
			(layer "B.Fab")
			(hide yes)
			(effects
				(font
					(size 1 1)
					(thickness 0.15)
				)
				(justify mirror)
			)
		)
		(property "Manufacturer" "Hirose Electric"
			(at 124.35 397.704 0)
			(layer "B.Fab")
			(hide yes)
			(effects
				(font
					(size 1 1)
					(thickness 0.15)
				)
				(justify mirror)
			)
		)
		(sheetname "SPI Flash + SD Card")
		(sheetfile "spi-flash.kicad_sch")
		(attr smd)
		(fp_line
			(start -7 8.11)
			(end -7 4.502)
			(stroke
				(width 0.15)
				(type solid)
			)
			(layer "B.SilkS")
		)
		(fp_line
			(start -6.553 8.11)
			(end -7 8.11)
			(stroke
				(width 0.15)
				(type solid)
			)
			(layer "B.SilkS")
		)
		(fp_line
			(start 5.049 8.11)
			(end 6.967 8.11)
			(stroke
				(width 0.15)
				(type solid)
			)
			(layer "B.SilkS")
		)
		(fp_line
			(start 6.967 8.11)
			(end 6.967 -5.897)
			(stroke
				(width 0.15)
				(type solid)
			)
			(layer "B.SilkS")
		)
		(fp_line
			(start -7 2.802)
			(end -7 -1.898)
			(stroke
				(width 0.15)
				(type solid)
			)
			(layer "B.SilkS")
		)
		(fp_line
			(start -7 -3.197)
			(end -7 -4.998)
			(stroke
				(width 0.15)
				(type solid)
			)
			(layer "B.SilkS")
		)
		(fp_line
			(start -3.9 -7.809)
			(end 2.47 -7.809)
			(stroke
				(width 0.15)
				(type solid)
			)
			(layer "B.SilkS")
		)
		(fp_line
			(start -3.9 -7.809)
			(end -3.9 -7.959)
			(stroke
				(width 0.15)
				(type solid)
			)
			(layer "B.SilkS")
		)
		(fp_line
			(start 5.488 -7.959)
			(end 5.749 -7.959)
			(stroke
				(width 0.15)
				(type solid)
			)
			(layer "B.SilkS")
		)
		(fp_line
			(start -5.971 -8.157)
			(end -6.17 -7.959)
			(stroke
				(width 0.15)
				(type solid)
			)
			(layer "B.SilkS")
		)
		(fp_line
			(start -5.971 -8.157)
			(end -4.111 -8.157)
			(stroke
				(width 0.15)
				(type solid)
			)
			(layer "B.SilkS")
		)
		(fp_line
			(start -4.111 -8.157)
			(end -3.9 -7.959)
			(stroke
				(width 0.15)
				(type solid)
			)
			(layer "B.SilkS")
		)
		(fp_line
			(start 2.979 -8.157)
			(end 2.47 -7.809)
			(stroke
				(width 0.15)
				(type solid)
			)
			(layer "B.SilkS")
		)
		(fp_line
			(start 5.289 -8.157)
			(end 5.488 -7.959)
			(stroke
				(width 0.15)
				(type solid)
			)
			(layer "B.SilkS")
		)
		(fp_line
			(start 5.289 -8.157)
			(end 2.979 -8.157)
			(stroke
				(width 0.15)
				(type solid)
			)
			(layer "B.SilkS")
		)
		(fp_circle
			(center 3.19 8.71)
			(end 3.239 8.71)
			(stroke
				(width 0.15)
				(type solid)
			)
			(fill yes)
			(layer "B.SilkS")
		)
		(fp_rect
			(start -7.7 8.9)
			(end 7.4 -8.6)
			(stroke
				(width 0.05)
				(type solid)
			)
			(fill no)
			(layer "B.CrtYd")
		)
		(fp_line
			(start 6.898 8.051)
			(end -6.951 8.051)
			(stroke
				(width 0.15)
				(type solid)
			)
			(layer "B.Fab")
		)
		(fp_line
			(start 2.483 -7.748)
			(end -3.94 -7.748)
			(stroke
				(width 0.15)
				(type solid)
			)
			(layer "B.Fab")
		)
		(fp_line
			(start -6.951 -7.898)
			(end -6.951 8.051)
			(stroke
				(width 0.15)
				(type solid)
			)
			(layer "B.Fab")
		)
		(fp_line
			(start -6.141 -7.898)
			(end -6.951 -7.898)
			(stroke
				(width 0.15)
				(type solid)
			)
			(layer "B.Fab")
		)
		(fp_line
			(start -3.94 -7.898)
			(end -3.94 -7.748)
			(stroke
				(width 0.15)
				(type solid)
			)
			(layer "B.Fab")
		)
		(fp_line
			(start -3.94 -7.898)
			(end -4.141 -8.099)
			(stroke
				(width 0.15)
				(type solid)
			)
			(layer "B.Fab")
		)
		(fp_line
			(start 5.459 -7.898)
			(end 6.898 -7.898)
			(stroke
				(width 0.15)
				(type solid)
			)
			(layer "B.Fab")
		)
		(fp_line
			(start 6.898 -7.898)
			(end 6.898 8.051)
			(stroke
				(width 0.15)
				(type solid)
			)
			(layer "B.Fab")
		)
		(fp_line
			(start -5.951 -8.099)
			(end -5.951 -12.998)
			(stroke
				(width 0.15)
				(type solid)
			)
			(layer "B.Fab")
		)
		(fp_line
			(start -5.941 -8.099)
			(end -6.141 -7.898)
			(stroke
				(width 0.15)
				(type solid)
			)
			(layer "B.Fab")
		)
		(fp_line
			(start -4.141 -8.099)
			(end -5.941 -8.099)
			(stroke
				(width 0.15)
				(type solid)
			)
			(layer "B.Fab")
		)
		(fp_line
			(start 3.01 -8.099)
			(end 2.483 -7.748)
			(stroke
				(width 0.15)
				(type solid)
			)
			(layer "B.Fab")
		)
		(fp_line
			(start 5.259 -8.099)
			(end 5.459 -7.898)
			(stroke
				(width 0.15)
				(type solid)
			)
			(layer "B.Fab")
		)
		(fp_line
			(start 5.259 -8.099)
			(end 3.01 -8.099)
			(stroke
				(width 0.15)
				(type solid)
			)
			(layer "B.Fab")
		)
		(fp_line
			(start -5.451 -9.497)
			(end 4.549 -9.497)
			(stroke
				(width 0.15)
				(type solid)
			)
			(layer "B.Fab")
		)
		(fp_line
			(start 5.049 -12.998)
			(end 5.049 -8.099)
			(stroke
				(width 0.15)
				(type solid)
			)
			(layer "B.Fab")
		)
		(fp_line
			(start -5.451 -13.498)
			(end 4.549 -13.498)
			(stroke
				(width 0.15)
				(type solid)
			)
			(layer "B.Fab")
		)
		(fp_arc
			(start -5.951 -8.997)
			(mid -5.8055 -9.3515)
			(end -5.451 -9.497)
			(stroke
				(width 0.15)
				(type solid)
			)
			(layer "B.Fab")
		)
		(fp_arc
			(start 4.549 -9.497)
			(mid 4.903498 -9.351498)
			(end 5.049 -8.997)
			(stroke
				(width 0.15)
				(type solid)
			)
			(layer "B.Fab")
		)
		(fp_arc
			(start -5.951 -12.998)
			(mid -5.805 -13.352)
			(end -5.451 -13.498)
			(stroke
				(width 0.15)
				(type solid)
			)
			(layer "B.Fab")
		)
		(fp_arc
			(start 4.549 -13.498)
			(mid 4.903 -13.352)
			(end 5.049 -12.998)
			(stroke
				(width 0.15)
				(type solid)
			)
			(layer "B.Fab")
		)
		(pad "1" smd rect
			(at 2.749 7.952 270)
			(size 0.7 1.2)
			(layers "B.Cu" "B.Mask" "B.Paste")
			(net 327 "Net-(J23-DAT2)")
			(pinfunction "DAT2")
			(pintype "bidirectional")
		)
		(pad "2" smd rect
			(at 1.65 7.952 270)
			(size 0.7 1.2)
			(layers "B.Cu" "B.Mask" "B.Paste")
			(net 328 "Net-(J23-DAT3{slash}CD)")
			(pinfunction "DAT3/CD")
			(pintype "bidirectional")
		)
		(pad "3" smd rect
			(at 0.549 7.952 270)
			(size 0.7 1.2)
			(layers "B.Cu" "B.Mask" "B.Paste")
			(net 329 "Net-(J23-CMD)")
			(pinfunction "CMD")
			(pintype "input")
		)
		(pad "4" smd rect
			(at -0.552 7.952 270)
			(size 0.7 1.2)
			(layers "B.Cu" "B.Mask" "B.Paste")
			(net 24 "+3V3")
			(pinfunction "VDD")
			(pintype "power_in")
		)
		(pad "5" smd rect
			(at -1.651 7.952 270)
			(size 0.7 1.2)
			(layers "B.Cu" "B.Mask" "B.Paste")
			(net 330 "Net-(J23-CLK)")
			(pinfunction "CLK")
			(pintype "input")
		)
		(pad "6" smd rect
			(at -2.751 7.952 270)
			(size 0.7 1.2)
			(layers "B.Cu" "B.Mask" "B.Paste")
			(net 1 "GND")
			(pinfunction "VSS")
			(pintype "power_in")
		)
		(pad "7" smd rect
			(at -3.851 7.952 270)
			(size 0.7 1.2)
			(layers "B.Cu" "B.Mask" "B.Paste")
			(net 331 "Net-(J23-DAT0)")
			(pinfunction "DAT0")
			(pintype "input")
		)
		(pad "8" smd rect
			(at -4.951 7.952 270)
			(size 0.7 1.2)
			(layers "B.Cu" "B.Mask" "B.Paste")
			(net 332 "Net-(J23-DAT1)")
			(pinfunction "DAT1")
			(pintype "input")
		)
		(pad "9" smd rect
			(at -5.901 7.952 270)
			(size 0.7 1.2)
			(layers "B.Cu" "B.Mask" "B.Paste")
			(net 1 "GND")
			(pinfunction "DET_B")
			(pintype "passive")
		)
		(pad "10" smd rect
			(at -6.851 -2.547 270)
			(size 1 0.8)
			(layers "B.Cu" "B.Mask" "B.Paste")
			(net 74 "/SPI Flash + SD Card/SD_CARD_~{CD}")
			(pinfunction "DET_A")
			(pintype "passive")
		)
		(pad "11" smd rect
			(at -6.851 -6.698 270)
			(size 1 2.8)
			(layers "B.Cu" "B.Mask" "B.Paste")
			(net 16 "Net-(J23-SHIELD)")
			(pinfunction "SHIELD")
			(pintype "passive")
		)
		(pad "11" smd rect
			(at -6.851 3.652 270)
			(size 1 1.2)
			(layers "B.Cu" "B.Mask" "B.Paste")
			(net 16 "Net-(J23-SHIELD)")
			(pinfunction "SHIELD")
			(pintype "passive")
		)
		(pad "11" smd rect
			(at 4.299 7.952 270)
			(size 1 1.2)
			(layers "B.Cu" "B.Mask" "B.Paste")
			(net 16 "Net-(J23-SHIELD)")
			(pinfunction "SHIELD")
			(pintype "passive")
		)
		(pad "11" smd rect
			(at 6.648 -7.148 270)
			(size 1.3 1.9)
			(layers "B.Cu" "B.Mask" "B.Paste")
			(net 16 "Net-(J23-SHIELD)")
			(pinfunction "SHIELD")
			(pintype "passive")
		)
	)
	(footprint "antmicro-footprints:R_0402_1005Metric"
		(layer "B.Cu")
		(at 261.5 86.2)
		(descr "Resistor SMD 0402")
		(tags "resistor SMD 0402")
		(property "Reference" "R108"
			(at 1.4 1.275 180)
			(layer "B.SilkS")
			(effects
				(font
					(size 0.7 0.7)
					(thickness 0.15)
				)
				(justify left bottom mirror)
			)
		)
		(property "Value" "R_1k_0402"
			(at 0 -1.4 180)
			(layer "B.Fab")
			(effects
				(font
					(size 0.7 0.7)
					(thickness 0.15)
				)
				(justify left bottom mirror)
			)
		)
		(property "Description" "SMD Chip Resistor, 1 kohm, ± 1%, 63 mW, 0402 [1005 Metric], Thick Film, General Purpose"
			(at 0 0 0)
			(layer "F.Fab")
			(hide yes)
			(effects
				(font
					(size 1.27 1.27)
					(thickness 0.15)
				)
			)
		)
		(property "Author" "Antmicro"
			(at 0 0 0)
			(layer "B.Fab")
			(hide yes)
			(effects
				(font
					(size 1 1)
					(thickness 0.15)
				)
				(justify mirror)
			)
		)
		(property "License" "Apache-2.0"
			(at 0 0 0)
			(layer "B.Fab")
			(hide yes)
			(effects
				(font
					(size 1 1)
					(thickness 0.15)
				)
				(justify mirror)
			)
		)
		(property "MPN" "CR0402-FX-1001GLF"
			(at 0 0 0)
			(layer "B.Fab")
			(hide yes)
			(effects
				(font
					(size 1 1)
					(thickness 0.15)
				)
				(justify mirror)
			)
		)
		(property "Manufacturer" "Bourns"
			(at 0 0 0)
			(layer "B.Fab")
			(hide yes)
			(effects
				(font
					(size 1 1)
					(thickness 0.15)
				)
				(justify mirror)
			)
		)
		(property "Tolerance" "1%"
			(at 0 0 0)
			(layer "B.Fab")
			(hide yes)
			(effects
				(font
					(size 1 1)
					(thickness 0.15)
				)
				(justify mirror)
			)
		)
		(property "Val" "1k"
			(at 0 0 0)
			(layer "B.Fab")
			(hide yes)
			(effects
				(font
					(size 1 1)
					(thickness 0.15)
				)
				(justify mirror)
			)
		)
		(sheetname "User GPIO + LED + button + DIP switch")
		(sheetfile "user-gpio.kicad_sch")
		(attr smd)
		(fp_rect
			(start -0.925 0.47)
			(end 0.925 -0.47)
			(stroke
				(width 0.05)
				(type default)
			)
			(fill no)
			(layer "B.CrtYd")
		)
		(fp_rect
			(start -0.5 0.25)
			(end 0.5 -0.25)
			(stroke
				(width 0.15)
				(type solid)
			)
			(fill no)
			(layer "B.Fab")
		)
		(pad "1" smd roundrect
			(at -0.48 0)
			(size 0.59 0.64)
			(layers "B.Cu" "B.Mask" "B.Paste")
			(roundrect_rratio 0.25)
			(net 24 "+3V3")
			(pintype "passive")
		)
		(pad "2" smd roundrect
			(at 0.48 0)
			(size 0.59 0.64)
			(layers "B.Cu" "B.Mask" "B.Paste")
			(roundrect_rratio 0.25)
			(net 777 "Net-(D19-A)")
			(pintype "passive")
		)
	)
	(footprint "antmicro-footprints:C_0603_1608Metric"
		(layer "B.Cu")
		(at 200 118.3 90)
		(descr "Capacitor SMD 0603")
		(tags "capacitor 0603")
		(property "Reference" "C106"
			(at 5.275 -0.725 270)
			(layer "B.SilkS")
			(effects
				(font
					(size 0.7 0.7)
					(thickness 0.15)
				)
				(justify left bottom mirror)
			)
		)
		(property "Value" "C_47u_0603"
			(at 0 -1.6 270)
			(layer "B.Fab")
			(effects
				(font
					(size 0.7 0.7)
					(thickness 0.15)
				)
				(justify left bottom mirror)
			)
		)
		(property "Description" "SMD Multilayer Ceramic Capacitor, 47 µF, 6.3 V, 0603 [1608 Metric], ± 20%, X5R, GRM Series"
			(at 0 0 90)
			(layer "F.Fab")
			(hide yes)
			(effects
				(font
					(size 1.27 1.27)
					(thickness 0.15)
				)
			)
		)
		(property "Author" "Antmicro"
			(at 318.3 -81.7 0)
			(layer "B.Fab")
			(hide yes)
			(effects
				(font
					(size 1 1)
					(thickness 0.15)
				)
				(justify mirror)
			)
		)
		(property "Dielectric" ""
			(at 318.3 -81.7 0)
			(layer "B.Fab")
			(hide yes)
			(effects
				(font
					(size 1 1)
					(thickness 0.15)
				)
				(justify mirror)
			)
		)
		(property "License" "Apache-2.0"
			(at 318.3 -81.7 0)
			(layer "B.Fab")
			(hide yes)
			(effects
				(font
					(size 1 1)
					(thickness 0.15)
				)
				(justify mirror)
			)
		)
		(property "MPN" "GRM188R60J476ME15D"
			(at 318.3 -81.7 0)
			(layer "B.Fab")
			(hide yes)
			(effects
				(font
					(size 1 1)
					(thickness 0.15)
				)
				(justify mirror)
			)
		)
		(property "Manufacturer" "Murata"
			(at 318.3 -81.7 0)
			(layer "B.Fab")
			(hide yes)
			(effects
				(font
					(size 1 1)
					(thickness 0.15)
				)
				(justify mirror)
			)
		)
		(property "Val" "47u"
			(at 318.3 -81.7 0)
			(layer "B.Fab")
			(hide yes)
			(effects
				(font
					(size 1 1)
					(thickness 0.15)
				)
				(justify mirror)
			)
		)
		(property "Voltage" ""
			(at 318.3 -81.7 0)
			(layer "B.Fab")
			(hide yes)
			(effects
				(font
					(size 1 1)
					(thickness 0.15)
				)
				(justify mirror)
			)
		)
		(sheetname "FPGA Bank 18 & 32")
		(sheetfile "fpga-bank-18-32.kicad_sch")
		(attr smd)
		(fp_line
			(start -0.15 -0.4)
			(end 0.15 -0.4)
			(stroke
				(width 0.15)
				(type solid)
			)
			(layer "B.SilkS")
		)
		(fp_line
			(start -0.15 0.4)
			(end 0.15 0.4)
			(stroke
				(width 0.15)
				(type solid)
			)
			(layer "B.SilkS")
		)
		(fp_rect
			(start -1.25 0.65)
			(end 1.25 -0.65)
			(stroke
				(width 0.05)
				(type solid)
			)
			(fill no)
			(layer "B.CrtYd")
		)
		(fp_rect
			(start -0.8 0.4)
			(end 0.8 -0.4)
			(stroke
				(width 0.15)
				(type solid)
			)
			(fill no)
			(layer "B.Fab")
		)
		(pad "1" smd roundrect
			(at -0.7 0 90)
			(size 0.8 1)
			(layers "B.Cu" "B.Mask" "B.Paste")
			(roundrect_rratio 0.2)
			(net 24 "+3V3")
			(pintype "passive")
		)
		(pad "2" smd roundrect
			(at 0.7 0 90)
			(size 0.8 1)
			(layers "B.Cu" "B.Mask" "B.Paste")
			(roundrect_rratio 0.2)
			(net 1 "GND")
			(pintype "passive")
		)
	)
	(footprint "antmicro-footprints:C_0402_1005Metric"
		(layer "B.Cu")
		(at 213.5 132 -90)
		(descr "Capacitor SMD 0402")
		(tags "capacitor SMD 0402")
		(property "Reference" "C19"
			(at -1.075 -1.325 90)
			(layer "B.SilkS")
			(effects
				(font
					(size 0.7 0.7)
					(thickness 0.15)
				)
				(justify left bottom mirror)
			)
		)
		(property "Value" "C_100n_0402"
			(at 0 -1.169 90)
			(layer "B.Fab")
			(effects
				(font
					(size 0.7 0.7)
					(thickness 0.15)
				)
				(justify left bottom mirror)
			)
		)
		(property "Description" "SMD Multilayer Ceramic Capacitor, 0.1 µF, 50 V, 0402 [1005 Metric], ± 10%, X5R, GRM Series"
			(at 0 0 270)
			(layer "F.Fab")
			(hide yes)
			(effects
				(font
					(size 1.27 1.27)
					(thickness 0.15)
				)
			)
		)
		(property "Author" "Antmicro"
			(at 81.5 345.5 0)
			(layer "B.Fab")
			(hide yes)
			(effects
				(font
					(size 1 1)
					(thickness 0.15)
				)
				(justify mirror)
			)
		)
		(property "Dielectric" "X5R"
			(at 81.5 345.5 0)
			(layer "B.Fab")
			(hide yes)
			(effects
				(font
					(size 1 1)
					(thickness 0.15)
				)
				(justify mirror)
			)
		)
		(property "License" "Apache-2.0"
			(at 81.5 345.5 0)
			(layer "B.Fab")
			(hide yes)
			(effects
				(font
					(size 1 1)
					(thickness 0.15)
				)
				(justify mirror)
			)
		)
		(property "MPN" "GRM155R61H104KE14D"
			(at 81.5 345.5 0)
			(layer "B.Fab")
			(hide yes)
			(effects
				(font
					(size 1 1)
					(thickness 0.15)
				)
				(justify mirror)
			)
		)
		(property "Manufacturer" "Murata"
			(at 81.5 345.5 0)
			(layer "B.Fab")
			(hide yes)
			(effects
				(font
					(size 1 1)
					(thickness 0.15)
				)
				(justify mirror)
			)
		)
		(property "Val" "100n"
			(at 81.5 345.5 0)
			(layer "B.Fab")
			(hide yes)
			(effects
				(font
					(size 1 1)
					(thickness 0.15)
				)
				(justify mirror)
			)
		)
		(property "Voltage" "50V"
			(at 81.5 345.5 0)
			(layer "B.Fab")
			(hide yes)
			(effects
				(font
					(size 1 1)
					(thickness 0.15)
				)
				(justify mirror)
			)
		)
		(sheetname "FPGA Bank 14 & 15")
		(sheetfile "fpga-bank-14-15.kicad_sch")
		(attr smd)
		(fp_rect
			(start -0.925 0.47)
			(end 0.925 -0.47)
			(stroke
				(width 0.05)
				(type default)
			)
			(fill no)
			(layer "B.CrtYd")
		)
		(fp_line
			(start -0.494 0.25)
			(end 0.504 0.25)
			(stroke
				(width 0.15)
				(type solid)
			)
			(layer "B.Fab")
		)
		(fp_line
			(start 0.504 0.25)
			(end 0.504 -0.248)
			(stroke
				(width 0.15)
				(type solid)
			)
			(layer "B.Fab")
		)
		(fp_line
			(start -0.494 -0.248)
			(end -0.494 0.25)
			(stroke
				(width 0.15)
				(type solid)
			)
			(layer "B.Fab")
		)
		(fp_line
			(start 0.504 -0.248)
			(end -0.494 -0.248)
			(stroke
				(width 0.15)
				(type solid)
			)
			(layer "B.Fab")
		)
		(pad "1" smd roundrect
			(at -0.48 0 270)
			(size 0.59 0.64)
			(layers "B.Cu" "B.Mask" "B.Paste")
			(roundrect_rratio 0.25)
			(net 1 "GND")
			(pintype "passive")
		)
		(pad "2" smd roundrect
			(at 0.48 0 270)
			(size 0.59 0.64)
			(layers "B.Cu" "B.Mask" "B.Paste")
			(roundrect_rratio 0.25)
			(net 24 "+3V3")
			(pintype "passive")
		)
	)
)
